(kicad_pcb
	(version 20260206)
	(generator "pcbnew")
	(generator_version "10.0")
	(general
		(thickness 1.6)
		(legacy_teardrops no)
	)
	(paper "A4")
	(title_block
		(title "04192023_DAF0TMB3IC0_F0TG_MB_C_brd_V02_OCP.brd")
		(comment 1 "Grand Teton / footprints 3413-3420 of 8354")
	)
	(layers
		(0 "F.Cu" signal "TOP")
		(4 "In1.Cu" signal "GND")
		(6 "In2.Cu" signal "IN1")
		(8 "In3.Cu" signal "GND1")
		(10 "In4.Cu" signal "IN2")
		(12 "In5.Cu" signal "GND2")
		(14 "In6.Cu" signal "IN3")
		(16 "In7.Cu" signal "GND3")
		(18 "In8.Cu" signal "VCC")
		(20 "In9.Cu" signal "VCC1")
		(22 "In10.Cu" signal "GND4")
		(24 "In11.Cu" signal "IN4")
		(26 "In12.Cu" signal "GND5")
		(28 "In13.Cu" signal "IN5")
		(30 "In14.Cu" signal "GND6")
		(32 "In15.Cu" signal "IN6")
		(34 "In16.Cu" signal "GND7")
		(2 "B.Cu" signal "BOTTOM")
		(9 "F.Adhes" user "F.Adhesive")
		(11 "B.Adhes" user "B.Adhesive")
		(13 "F.Paste" user "Package Geometry/Pastemask Top")
		(15 "B.Paste" user "Package Geometry/Pastemask Bottom")
		(5 "F.SilkS" user "Ref Des/Silkscreen Top")
		(7 "B.SilkS" user "Ref Des/Silkscreen Bottom")
		(1 "F.Mask" user "Board Geometry/Soldermask Top")
		(3 "B.Mask" user "Board Geometry/Soldermask Bottom")
		(17 "Dwgs.User" user "User.Drawings")
		(19 "Cmts.User" user "User.Comments")
		(21 "Eco1.User" user "User.Eco1")
		(23 "Eco2.User" user "User.Eco2")
		(25 "Edge.Cuts" user "Board Geometry/Outline")
		(27 "Margin" user)
		(31 "F.CrtYd" user "Package Geometry/Place Bound Top")
		(29 "B.CrtYd" user "Package Geometry/Place Bound Bottom")
		(35 "F.Fab" user "Ref Des/Assembly Top")
		(33 "B.Fab" user "Ref Des/Assembly Bottom")
	)
	(footprint ""
		(layer "F.Cu")
		(at 349.032322 -155.927806)
		(property "Reference" "PR431"
			(at 0 0 0)
			(layer "F.SilkS")
			(hide yes)
			(effects
				(font
					(size 1.27 1.27)
				)
			)
		)
		(property "Value" ""
			(at 0 0 0)
			(layer "F.Fab")
			(effects
				(font
					(size 1.27 1.27)
				)
			)
		)
		(duplicate_pad_numbers_are_jumpers no)
		(fp_line
			(start -0.7874 -0.4064)
			(end 0.7874 -0.4064)
			(stroke
				(width 0.1524)
				(type default)
			)
			(layer "F.SilkS")
		)
		(fp_line
			(start -0.7874 0.4064)
			(end -0.7874 -0.4064)
			(stroke
				(width 0.1524)
				(type default)
			)
			(layer "F.SilkS")
		)
		(fp_line
			(start 0.7874 -0.4064)
			(end 0.7874 0.4064)
			(stroke
				(width 0.1524)
				(type default)
			)
			(layer "F.SilkS")
		)
		(fp_line
			(start 0.7874 0.4064)
			(end -0.7874 0.4064)
			(stroke
				(width 0.1524)
				(type default)
			)
			(layer "F.SilkS")
		)
		(fp_line
			(start -0.67945 -0.305054)
			(end -0.12065 -0.305054)
			(stroke
				(width 0.1)
				(type default)
			)
			(layer "F.Fab")
		)
		(fp_line
			(start -0.67945 0.3048)
			(end -0.67945 -0.305054)
			(stroke
				(width 0.1)
				(type default)
			)
			(layer "F.Fab")
		)
		(fp_line
			(start -0.12065 -0.305054)
			(end -0.12065 -0.2794)
			(stroke
				(width 0.1)
				(type default)
			)
			(layer "F.Fab")
		)
		(fp_line
			(start -0.12065 -0.2794)
			(end 0.12065 -0.2794)
			(stroke
				(width 0.1)
				(type default)
			)
			(layer "F.Fab")
		)
		(fp_line
			(start -0.12065 0.2794)
			(end -0.12065 0.3048)
			(stroke
				(width 0.1)
				(type default)
			)
			(layer "F.Fab")
		)
		(fp_line
			(start -0.12065 0.3048)
			(end -0.67945 0.3048)
			(stroke
				(width 0.1)
				(type default)
			)
			(layer "F.Fab")
		)
		(fp_line
			(start 0.120396 0.2794)
			(end -0.12065 0.2794)
			(stroke
				(width 0.1)
				(type default)
			)
			(layer "F.Fab")
		)
		(fp_line
			(start 0.120396 0.3048)
			(end 0.120396 0.2794)
			(stroke
				(width 0.1)
				(type default)
			)
			(layer "F.Fab")
		)
		(fp_line
			(start 0.12065 -0.3048)
			(end 0.67945 -0.3048)
			(stroke
				(width 0.1)
				(type default)
			)
			(layer "F.Fab")
		)
		(fp_line
			(start 0.12065 -0.2794)
			(end 0.12065 -0.3048)
			(stroke
				(width 0.1)
				(type default)
			)
			(layer "F.Fab")
		)
		(fp_line
			(start 0.67945 -0.3048)
			(end 0.67945 0.3048)
			(stroke
				(width 0.1)
				(type default)
			)
			(layer "F.Fab")
		)
		(fp_line
			(start 0.67945 0.3048)
			(end 0.120396 0.3048)
			(stroke
				(width 0.1)
				(type default)
			)
			(layer "F.Fab")
		)
		(pad "1" smd circle
			(at -0.40005 0)
			(size 0 0)
			(layers "F.Cu" "F.Mask" "F.Paste")
			(net "GND")
		)
		(pad "2" smd circle
			(at 0.40005 0)
			(size 0 0)
			(layers "F.Cu" "F.Mask" "F.Paste")
			(net "PVDDCR_CPU0_P0_LSET6")
		)
	)
	(footprint ""
		(layer "F.Cu")
		(at 138.981942 -385.5212 90)
		(property "Reference" "R902"
			(at 0 0 90)
			(layer "F.SilkS")
			(hide yes)
			(effects
				(font
					(size 1.27 1.27)
				)
			)
		)
		(property "Value" ""
			(at 0 0 90)
			(layer "F.Fab")
			(effects
				(font
					(size 1.27 1.27)
				)
			)
		)
		(duplicate_pad_numbers_are_jumpers no)
		(fp_line
			(start 0.32512 -0.175006)
			(end 0.32512 0.175006)
			(stroke
				(width 0.1)
				(type default)
			)
			(layer "F.Fab")
		)
		(fp_line
			(start -0.32512 -0.175006)
			(end 0.32512 -0.175006)
			(stroke
				(width 0.1)
				(type default)
			)
			(layer "F.Fab")
		)
		(fp_line
			(start 0.32512 0.175006)
			(end -0.32512 0.175006)
			(stroke
				(width 0.1)
				(type default)
			)
			(layer "F.Fab")
		)
		(fp_line
			(start -0.32512 0.175006)
			(end -0.32512 -0.175006)
			(stroke
				(width 0.1)
				(type default)
			)
			(layer "F.Fab")
		)
		(pad "1" smd rect
			(at -0.2667 0 90)
			(size 0.3048 0.381)
			(layers "F.Cu" "F.Mask" "F.Paste")
			(net "P1V8_CPU1_RT_1D")
		)
		(pad "2" smd rect
			(at 0.2667 0 270)
			(size 0.3048 0.381)
			(layers "F.Cu" "F.Mask" "F.Paste")
			(net "RT_CPU1_P3_ADDR3")
		)
	)
	(footprint ""
		(layer "F.Cu")
		(at 148.971 -116.713 -90)
		(property "Reference" "C9004"
			(at 0 0 270)
			(layer "F.SilkS")
			(hide yes)
			(effects
				(font
					(size 1.27 1.27)
				)
			)
		)
		(property "Value" ""
			(at 0 0 270)
			(layer "F.Fab")
			(effects
				(font
					(size 1.27 1.27)
				)
			)
		)
		(duplicate_pad_numbers_are_jumpers no)
		(fp_line
			(start -0.7874 0.4064)
			(end -0.7874 -0.4064)
			(stroke
				(width 0.1524)
				(type default)
			)
			(layer "F.SilkS")
		)
		(fp_line
			(start 0.7874 0.4064)
			(end -0.7874 0.4064)
			(stroke
				(width 0.1524)
				(type default)
			)
			(layer "F.SilkS")
		)
		(fp_line
			(start -0.7874 -0.4064)
			(end 0.7874 -0.4064)
			(stroke
				(width 0.1524)
				(type default)
			)
			(layer "F.SilkS")
		)
		(fp_line
			(start 0.7874 -0.4064)
			(end 0.7874 0.4064)
			(stroke
				(width 0.1524)
				(type default)
			)
			(layer "F.SilkS")
		)
		(fp_line
			(start -0.67945 0.3048)
			(end -0.67945 -0.305054)
			(stroke
				(width 0.1)
				(type default)
			)
			(layer "F.Fab")
		)
		(fp_line
			(start -0.12065 0.3048)
			(end -0.67945 0.3048)
			(stroke
				(width 0.1)
				(type default)
			)
			(layer "F.Fab")
		)
		(fp_line
			(start 0.120396 0.3048)
			(end 0.120396 0.2794)
			(stroke
				(width 0.1)
				(type default)
			)
			(layer "F.Fab")
		)
		(fp_line
			(start 0.67945 0.3048)
			(end 0.120396 0.3048)
			(stroke
				(width 0.1)
				(type default)
			)
			(layer "F.Fab")
		)
		(fp_line
			(start -0.12065 0.2794)
			(end -0.12065 0.3048)
			(stroke
				(width 0.1)
				(type default)
			)
			(layer "F.Fab")
		)
		(fp_line
			(start 0.120396 0.2794)
			(end -0.12065 0.2794)
			(stroke
				(width 0.1)
				(type default)
			)
			(layer "F.Fab")
		)
		(fp_line
			(start -0.12065 -0.2794)
			(end 0.12065 -0.2794)
			(stroke
				(width 0.1)
				(type default)
			)
			(layer "F.Fab")
		)
		(fp_line
			(start 0.12065 -0.2794)
			(end 0.12065 -0.3048)
			(stroke
				(width 0.1)
				(type default)
			)
			(layer "F.Fab")
		)
		(fp_line
			(start 0.12065 -0.3048)
			(end 0.67945 -0.3048)
			(stroke
				(width 0.1)
				(type default)
			)
			(layer "F.Fab")
		)
		(fp_line
			(start 0.67945 -0.3048)
			(end 0.67945 0.3048)
			(stroke
				(width 0.1)
				(type default)
			)
			(layer "F.Fab")
		)
		(fp_line
			(start -0.67945 -0.305054)
			(end -0.12065 -0.305054)
			(stroke
				(width 0.1)
				(type default)
			)
			(layer "F.Fab")
		)
		(fp_line
			(start -0.12065 -0.305054)
			(end -0.12065 -0.2794)
			(stroke
				(width 0.1)
				(type default)
			)
			(layer "F.Fab")
		)
		(pad "1" smd circle
			(at -0.40005 0 270)
			(size 0 0)
			(layers "F.Cu" "F.Mask" "F.Paste")
			(net "U206_VS")
		)
		(pad "2" smd circle
			(at 0.40005 0 270)
			(size 0 0)
			(layers "F.Cu" "F.Mask" "F.Paste")
			(net "GND")
		)
	)
	(footprint ""
		(layer "F.Cu")
		(at 114.299238 -41.17975 -90)
		(property "Reference" "R6289"
			(at 0 0 270)
			(layer "F.SilkS")
			(hide yes)
			(effects
				(font
					(size 1.27 1.27)
				)
			)
		)
		(property "Value" ""
			(at 0 0 270)
			(layer "F.Fab")
			(effects
				(font
					(size 1.27 1.27)
				)
			)
		)
		(duplicate_pad_numbers_are_jumpers no)
		(fp_line
			(start -0.7874 0.4064)
			(end -0.7874 -0.4064)
			(stroke
				(width 0.1524)
				(type default)
			)
			(layer "F.SilkS")
		)
		(fp_line
			(start 0.7874 0.4064)
			(end -0.7874 0.4064)
			(stroke
				(width 0.1524)
				(type default)
			)
			(layer "F.SilkS")
		)
		(fp_line
			(start -0.7874 -0.4064)
			(end 0.7874 -0.4064)
			(stroke
				(width 0.1524)
				(type default)
			)
			(layer "F.SilkS")
		)
		(fp_line
			(start 0.7874 -0.4064)
			(end 0.7874 0.4064)
			(stroke
				(width 0.1524)
				(type default)
			)
			(layer "F.SilkS")
		)
		(fp_line
			(start -0.67945 0.3048)
			(end -0.67945 -0.305054)
			(stroke
				(width 0.1)
				(type default)
			)
			(layer "F.Fab")
		)
		(fp_line
			(start -0.12065 0.3048)
			(end -0.67945 0.3048)
			(stroke
				(width 0.1)
				(type default)
			)
			(layer "F.Fab")
		)
		(fp_line
			(start 0.120396 0.3048)
			(end 0.120396 0.2794)
			(stroke
				(width 0.1)
				(type default)
			)
			(layer "F.Fab")
		)
		(fp_line
			(start 0.67945 0.3048)
			(end 0.120396 0.3048)
			(stroke
				(width 0.1)
				(type default)
			)
			(layer "F.Fab")
		)
		(fp_line
			(start -0.12065 0.2794)
			(end -0.12065 0.3048)
			(stroke
				(width 0.1)
				(type default)
			)
			(layer "F.Fab")
		)
		(fp_line
			(start 0.120396 0.2794)
			(end -0.12065 0.2794)
			(stroke
				(width 0.1)
				(type default)
			)
			(layer "F.Fab")
		)
		(fp_line
			(start -0.12065 -0.2794)
			(end 0.12065 -0.2794)
			(stroke
				(width 0.1)
				(type default)
			)
			(layer "F.Fab")
		)
		(fp_line
			(start 0.12065 -0.2794)
			(end 0.12065 -0.3048)
			(stroke
				(width 0.1)
				(type default)
			)
			(layer "F.Fab")
		)
		(fp_line
			(start 0.12065 -0.3048)
			(end 0.67945 -0.3048)
			(stroke
				(width 0.1)
				(type default)
			)
			(layer "F.Fab")
		)
		(fp_line
			(start 0.67945 -0.3048)
			(end 0.67945 0.3048)
			(stroke
				(width 0.1)
				(type default)
			)
			(layer "F.Fab")
		)
		(fp_line
			(start -0.67945 -0.305054)
			(end -0.12065 -0.305054)
			(stroke
				(width 0.1)
				(type default)
			)
			(layer "F.Fab")
		)
		(fp_line
			(start -0.12065 -0.305054)
			(end -0.12065 -0.2794)
			(stroke
				(width 0.1)
				(type default)
			)
			(layer "F.Fab")
		)
		(pad "1" smd circle
			(at -0.40005 0 270)
			(size 0 0)
			(layers "F.Cu" "F.Mask" "F.Paste")
			(net "P3V3_AUX")
		)
		(pad "2" smd circle
			(at 0.40005 0 270)
			(size 0 0)
			(layers "F.Cu" "F.Mask" "F.Paste")
			(net "USB_HUB2_MRP_VBUS_DET")
		)
	)
	(footprint ""
		(layer "F.Cu")
		(at 279.056592 -346.866464 -90)
		(property "Reference" "PC180_4"
			(at 0 0 270)
			(layer "F.SilkS")
			(hide yes)
			(effects
				(font
					(size 1.27 1.27)
				)
			)
		)
		(property "Value" ""
			(at 0 0 270)
			(layer "F.Fab")
			(effects
				(font
					(size 1.27 1.27)
				)
			)
		)
		(duplicate_pad_numbers_are_jumpers no)
		(fp_line
			(start -0.7874 0.4064)
			(end -0.7874 -0.4064)
			(stroke
				(width 0.1524)
				(type default)
			)
			(layer "F.SilkS")
		)
		(fp_line
			(start 0.7874 0.4064)
			(end -0.7874 0.4064)
			(stroke
				(width 0.1524)
				(type default)
			)
			(layer "F.SilkS")
		)
		(fp_line
			(start -0.7874 -0.4064)
			(end 0.7874 -0.4064)
			(stroke
				(width 0.1524)
				(type default)
			)
			(layer "F.SilkS")
		)
		(fp_line
			(start 0.7874 -0.4064)
			(end 0.7874 0.4064)
			(stroke
				(width 0.1524)
				(type default)
			)
			(layer "F.SilkS")
		)
		(fp_line
			(start -0.67945 0.3048)
			(end -0.67945 -0.305054)
			(stroke
				(width 0.1)
				(type default)
			)
			(layer "F.Fab")
		)
		(fp_line
			(start -0.12065 0.3048)
			(end -0.67945 0.3048)
			(stroke
				(width 0.1)
				(type default)
			)
			(layer "F.Fab")
		)
		(fp_line
			(start 0.120396 0.3048)
			(end 0.120396 0.2794)
			(stroke
				(width 0.1)
				(type default)
			)
			(layer "F.Fab")
		)
		(fp_line
			(start 0.67945 0.3048)
			(end 0.120396 0.3048)
			(stroke
				(width 0.1)
				(type default)
			)
			(layer "F.Fab")
		)
		(fp_line
			(start -0.12065 0.2794)
			(end -0.12065 0.3048)
			(stroke
				(width 0.1)
				(type default)
			)
			(layer "F.Fab")
		)
		(fp_line
			(start 0.120396 0.2794)
			(end -0.12065 0.2794)
			(stroke
				(width 0.1)
				(type default)
			)
			(layer "F.Fab")
		)
		(fp_line
			(start -0.12065 -0.2794)
			(end 0.12065 -0.2794)
			(stroke
				(width 0.1)
				(type default)
			)
			(layer "F.Fab")
		)
		(fp_line
			(start 0.12065 -0.2794)
			(end 0.12065 -0.3048)
			(stroke
				(width 0.1)
				(type default)
			)
			(layer "F.Fab")
		)
		(fp_line
			(start 0.12065 -0.3048)
			(end 0.67945 -0.3048)
			(stroke
				(width 0.1)
				(type default)
			)
			(layer "F.Fab")
		)
		(fp_line
			(start 0.67945 -0.3048)
			(end 0.67945 0.3048)
			(stroke
				(width 0.1)
				(type default)
			)
			(layer "F.Fab")
		)
		(fp_line
			(start -0.67945 -0.305054)
			(end -0.12065 -0.305054)
			(stroke
				(width 0.1)
				(type default)
			)
			(layer "F.Fab")
		)
		(fp_line
			(start -0.12065 -0.305054)
			(end -0.12065 -0.2794)
			(stroke
				(width 0.1)
				(type default)
			)
			(layer "F.Fab")
		)
		(pad "1" smd circle
			(at -0.40005 0 270)
			(size 0 0)
			(layers "F.Cu" "F.Mask" "F.Paste")
			(net "SW_P12V_AUX_PVDDIO_P0_FLT")
		)
		(pad "2" smd circle
			(at 0.40005 0 270)
			(size 0 0)
			(layers "F.Cu" "F.Mask" "F.Paste")
			(net "GND")
		)
	)
	(footprint ""
		(layer "F.Cu")
		(at 110.067344 -375.94286 180)
		(property "Reference" "C1545"
			(at 0 0 180)
			(layer "F.SilkS")
			(hide yes)
			(effects
				(font
					(size 1.27 1.27)
				)
			)
		)
		(property "Value" ""
			(at 0 0 180)
			(layer "F.Fab")
			(effects
				(font
					(size 1.27 1.27)
				)
			)
		)
		(duplicate_pad_numbers_are_jumpers no)
		(fp_line
			(start 0.299974 0.150114)
			(end -0.299974 0.150114)
			(stroke
				(width 0.1)
				(type default)
			)
			(layer "F.Fab")
		)
		(fp_line
			(start 0.299974 -0.150114)
			(end 0.299974 0.150114)
			(stroke
				(width 0.1)
				(type default)
			)
			(layer "F.Fab")
		)
		(fp_line
			(start -0.299974 0.150114)
			(end -0.299974 -0.150114)
			(stroke
				(width 0.1)
				(type default)
			)
			(layer "F.Fab")
		)
		(fp_line
			(start -0.299974 -0.150114)
			(end 0.299974 -0.150114)
			(stroke
				(width 0.1)
				(type default)
			)
			(layer "F.Fab")
		)
		(pad "1" smd rect
			(at -0.2667 0 180)
			(size 0.3048 0.381)
			(layers "F.Cu" "F.Mask" "F.Paste")
			(net "P5E_CPU1_P3_TX_C_DP<1>")
		)
		(pad "2" smd rect
			(at 0.2667 0 180)
			(size 0.3048 0.381)
			(layers "F.Cu" "F.Mask" "F.Paste")
			(net "P5E_CPU1_P3_TX_DP<1>")
		)
	)
	(footprint ""
		(layer "F.Cu")
		(at 151.126444 -370.57203 -90)
		(property "Reference" "C761"
			(at 0 0 270)
			(layer "F.SilkS")
			(hide yes)
			(effects
				(font
					(size 1.27 1.27)
				)
			)
		)
		(property "Value" ""
			(at 0 0 270)
			(layer "F.Fab")
			(effects
				(font
					(size 1.27 1.27)
				)
			)
		)
		(duplicate_pad_numbers_are_jumpers no)
		(fp_line
			(start -0.299974 0.150114)
			(end -0.299974 -0.150114)
			(stroke
				(width 0.1)
				(type default)
			)
			(layer "F.Fab")
		)
		(fp_line
			(start 0.299974 0.150114)
			(end -0.299974 0.150114)
			(stroke
				(width 0.1)
				(type default)
			)
			(layer "F.Fab")
		)
		(fp_line
			(start -0.299974 -0.150114)
			(end 0.299974 -0.150114)
			(stroke
				(width 0.1)
				(type default)
			)
			(layer "F.Fab")
		)
		(fp_line
			(start 0.299974 -0.150114)
			(end 0.299974 0.150114)
			(stroke
				(width 0.1)
				(type default)
			)
			(layer "F.Fab")
		)
		(pad "1" smd rect
			(at -0.2667 0 270)
			(size 0.3048 0.381)
			(layers "F.Cu" "F.Mask" "F.Paste")
			(net "P5E_CPU1_P2_TX_C_DP<6>")
		)
		(pad "2" smd rect
			(at 0.2667 0 270)
			(size 0.3048 0.381)
			(layers "F.Cu" "F.Mask" "F.Paste")
			(net "P5E_CPU1_P2_TX_DP<6>")
		)
	)
	(footprint ""
		(layer "F.Cu")
		(at 461.593946 -107.043728)
		(property "Reference" "C592"
			(at 0 0 0)
			(layer "F.SilkS")
			(hide yes)
			(effects
				(font
					(size 1.27 1.27)
				)
			)
		)
		(property "Value" ""
			(at 0 0 0)
			(layer "F.Fab")
			(effects
				(font
					(size 1.27 1.27)
				)
			)
		)
		(duplicate_pad_numbers_are_jumpers no)
		(fp_line
			(start -0.7874 -0.4064)
			(end 0.7874 -0.4064)
			(stroke
				(width 0.1524)
				(type default)
			)
			(layer "F.SilkS")
		)
		(fp_line
			(start -0.7874 0.4064)
			(end -0.7874 -0.4064)
			(stroke
				(width 0.1524)
				(type default)
			)
			(layer "F.SilkS")
		)
		(fp_line
			(start 0.7874 -0.4064)
			(end 0.7874 0.4064)
			(stroke
				(width 0.1524)
				(type default)
			)
			(layer "F.SilkS")
		)
		(fp_line
			(start 0.7874 0.4064)
			(end -0.7874 0.4064)
			(stroke
				(width 0.1524)
				(type default)
			)
			(layer "F.SilkS")
		)
		(fp_line
			(start -0.67945 -0.305054)
			(end -0.12065 -0.305054)
			(stroke
				(width 0.1)
				(type default)
			)
			(layer "F.Fab")
		)
		(fp_line
			(start -0.67945 0.3048)
			(end -0.67945 -0.305054)
			(stroke
				(width 0.1)
				(type default)
			)
			(layer "F.Fab")
		)
		(fp_line
			(start -0.12065 -0.305054)
			(end -0.12065 -0.2794)
			(stroke
				(width 0.1)
				(type default)
			)
			(layer "F.Fab")
		)
		(fp_line
			(start -0.12065 -0.2794)
			(end 0.12065 -0.2794)
			(stroke
				(width 0.1)
				(type default)
			)
			(layer "F.Fab")
		)
		(fp_line
			(start -0.12065 0.2794)
			(end -0.12065 0.3048)
			(stroke
				(width 0.1)
				(type default)
			)
			(layer "F.Fab")
		)
		(fp_line
			(start -0.12065 0.3048)
			(end -0.67945 0.3048)
			(stroke
				(width 0.1)
				(type default)
			)
			(layer "F.Fab")
		)
		(fp_line
			(start 0.120396 0.2794)
			(end -0.12065 0.2794)
			(stroke
				(width 0.1)
				(type default)
			)
			(layer "F.Fab")
		)
		(fp_line
			(start 0.120396 0.3048)
			(end 0.120396 0.2794)
			(stroke
				(width 0.1)
				(type default)
			)
			(layer "F.Fab")
		)
		(fp_line
			(start 0.12065 -0.3048)
			(end 0.67945 -0.3048)
			(stroke
				(width 0.1)
				(type default)
			)
			(layer "F.Fab")
		)
		(fp_line
			(start 0.12065 -0.2794)
			(end 0.12065 -0.3048)
			(stroke
				(width 0.1)
				(type default)
			)
			(layer "F.Fab")
		)
		(fp_line
			(start 0.67945 -0.3048)
			(end 0.67945 0.3048)
			(stroke
				(width 0.1)
				(type default)
			)
			(layer "F.Fab")
		)
		(fp_line
			(start 0.67945 0.3048)
			(end 0.120396 0.3048)
			(stroke
				(width 0.1)
				(type default)
			)
			(layer "F.Fab")
		)
		(pad "1" smd circle
			(at -0.40005 0)
			(size 0 0)
			(layers "F.Cu" "F.Mask" "F.Paste")
			(net "P3V3_AUX")
		)
		(pad "2" smd circle
			(at 0.40005 0)
			(size 0 0)
			(layers "F.Cu" "F.Mask" "F.Paste")
			(net "GND")
		)
	)
)
